(kicad_pcb
	(version 20241229)
	(generator "pcbnew")
	(generator_version "9.0")
	(general
		(thickness 1.6642)
		(legacy_teardrops no)
	)
	(paper "A3")
	(title_block
		(title "PolarFire SoM")
		(date "2025-07-22")
		(rev "1.1.4")
		(company "Antmicro Ltd")
		(comment 1 "www.antmicro.com")
		(comment 9 "footprints 289-292 of 470")
	)
	(layers
		(0 "F.Cu" mixed)
		(4 "In1.Cu" power)
		(6 "In2.Cu" signal)
		(8 "In3.Cu" power)
		(10 "In4.Cu" signal)
		(12 "In5.Cu" power)
		(14 "In6.Cu" power)
		(16 "In7.Cu" signal)
		(18 "In8.Cu" power)
		(20 "In9.Cu" signal)
		(22 "In10.Cu" power)
		(24 "In11.Cu" signal)
		(26 "In12.Cu" signal)
		(2 "B.Cu" mixed)
		(9 "F.Adhes" user "F.Adhesive")
		(11 "B.Adhes" user "B.Adhesive")
		(13 "F.Paste" user)
		(15 "B.Paste" user)
		(5 "F.SilkS" user "F.Silkscreen")
		(7 "B.SilkS" user "B.Silkscreen")
		(1 "F.Mask" user)
		(3 "B.Mask" user)
		(17 "Dwgs.User" user "User.Drawings")
		(19 "Cmts.User" user "User.Comments")
		(21 "Eco1.User" user "User.Eco1")
		(23 "Eco2.User" user "User.Eco2")
		(25 "Edge.Cuts" user)
		(27 "Margin" user)
		(31 "F.CrtYd" user "F.Courtyard")
		(29 "B.CrtYd" user "B.Courtyard")
		(35 "F.Fab" user)
		(33 "B.Fab" user)
	)
	(footprint "antmicro-footprints:C_0402_1005Metric"
		(layer "B.Cu")
		(at 204.51 140.67 90)
		(descr "Capacitor SMD 0402")
		(tags "capacitor SMD 0402")
		(property "Reference" "C62"
			(at -1.42 1.46 270)
			(layer "B.SilkS")
			(effects
				(font
					(size 0.7 0.7)
					(thickness 0.15)
				)
				(justify right bottom mirror)
			)
		)
		(property "Value" "C_100n_0402"
			(at -1.022927 -2.155213 90)
			(layer "B.Fab")
			(hide yes)
			(effects
				(font
					(size 0.7 0.7)
					(thickness 0.15)
				)
				(justify right bottom mirror)
			)
		)
		(property "Datasheet" "https://www.murata.com/products/productdetail?partno=GRM155R61H104KE14%23"
			(at 0 0 90)
			(layer "F.Fab")
			(hide yes)
			(effects
				(font
					(size 1.27 1.27)
					(thickness 0.15)
				)
			)
		)
		(property "Description" "SMD Multilayer Ceramic Capacitor, 0.1 µF, 50 V, 0402 [1005 Metric], ± 10%, X5R, GRM Series"
			(at 0 0 90)
			(layer "F.Fab")
			(hide yes)
			(effects
				(font
					(size 1.27 1.27)
					(thickness 0.15)
				)
			)
		)
		(property "Author" "Antmicro"
			(at 345.18 -63.84 0)
			(layer "B.Fab")
			(hide yes)
			(effects
				(font
					(size 1 1)
					(thickness 0.15)
				)
				(justify mirror)
			)
		)
		(property "Dielectric" "X5R"
			(at 345.18 -63.84 0)
			(layer "B.Fab")
			(hide yes)
			(effects
				(font
					(size 1 1)
					(thickness 0.15)
				)
				(justify mirror)
			)
		)
		(property "License" "Apache-2.0"
			(at 345.18 -63.84 0)
			(layer "B.Fab")
			(hide yes)
			(effects
				(font
					(size 1 1)
					(thickness 0.15)
				)
				(justify mirror)
			)
		)
		(property "MPN" "GRM155R61H104KE14D"
			(at 345.18 -63.84 0)
			(layer "B.Fab")
			(hide yes)
			(effects
				(font
					(size 1 1)
					(thickness 0.15)
				)
				(justify mirror)
			)
		)
		(property "Manufacturer" "Murata"
			(at 345.18 -63.84 0)
			(layer "B.Fab")
			(hide yes)
			(effects
				(font
					(size 1 1)
					(thickness 0.15)
				)
				(justify mirror)
			)
		)
		(property "Public" ""
			(at 345.18 -63.84 0)
			(layer "B.Fab")
			(hide yes)
			(effects
				(font
					(size 1 1)
					(thickness 0.15)
				)
				(justify mirror)
			)
		)
		(property "Val" "100n"
			(at 345.18 -63.84 0)
			(layer "B.Fab")
			(hide yes)
			(effects
				(font
					(size 1 1)
					(thickness 0.15)
				)
				(justify mirror)
			)
		)
		(property "Voltage" "50V"
			(at 345.18 -63.84 0)
			(layer "B.Fab")
			(hide yes)
			(effects
				(font
					(size 1 1)
					(thickness 0.15)
				)
				(justify mirror)
			)
		)
		(sheetname "/FPGA Supply/")
		(sheetfile "fpga-supply.kicad_sch")
		(attr smd)
		(fp_rect
			(start -0.925 0.47)
			(end 0.925 -0.47)
			(stroke
				(width 0.05)
				(type default)
			)
			(fill no)
			(layer "B.CrtYd")
		)
		(fp_line
			(start 0.504 -0.248)
			(end -0.494 -0.248)
			(stroke
				(width 0.15)
				(type solid)
			)
			(layer "B.Fab")
		)
		(fp_line
			(start -0.494 -0.248)
			(end -0.494 0.25)
			(stroke
				(width 0.15)
				(type solid)
			)
			(layer "B.Fab")
		)
		(fp_line
			(start 0.504 0.25)
			(end 0.504 -0.248)
			(stroke
				(width 0.15)
				(type solid)
			)
			(layer "B.Fab")
		)
		(fp_line
			(start -0.494 0.25)
			(end 0.504 0.25)
			(stroke
				(width 0.15)
				(type solid)
			)
			(layer "B.Fab")
		)
		(fp_text user "Author: Antmicro"
			(at -0.939 -3.399 270)
			(layer "B.Fab")
			(effects
				(font
					(size 0.7 0.7)
					(thickness 0.15)
				)
				(justify left bottom mirror)
			)
		)
		(fp_text user "${REFERENCE}"
			(at -0.939 -4.599 270)
			(layer "B.Fab")
			(effects
				(font
					(size 0.7 0.7)
					(thickness 0.15)
				)
				(justify left bottom mirror)
			)
		)
		(fp_text user "License: Apache-2.0"
			(at -0.939 -5.799 270)
			(layer "B.Fab")
			(effects
				(font
					(size 0.7 0.7)
					(thickness 0.15)
				)
				(justify left bottom mirror)
			)
		)
		(pad "1" smd roundrect
			(at -0.48 0 90)
			(size 0.59 0.64)
			(layers "B.Cu" "B.Mask" "B.Paste")
			(roundrect_rratio 0.25)
			(net 417 "GND")
			(pintype "passive")
		)
		(pad "2" smd roundrect
			(at 0.48 0 90)
			(size 0.59 0.64)
			(layers "B.Cu" "B.Mask" "B.Paste")
			(roundrect_rratio 0.25)
			(net 649 "VDD")
			(pintype "passive")
		)
	)
	(footprint "antmicro-footprints:C_0402_1005Metric"
		(layer "B.Cu")
		(at 222.9 147.295 90)
		(descr "Capacitor SMD 0402")
		(tags "capacitor SMD 0402")
		(property "Reference" "C283"
			(at -3.725 0.87 90)
			(layer "B.SilkS")
			(effects
				(font
					(size 0.7 0.7)
					(thickness 0.15)
				)
				(justify right bottom mirror)
			)
		)
		(property "Value" "C_10u_0402"
			(at -1.022927 -2.155213 90)
			(layer "B.Fab")
			(hide yes)
			(effects
				(font
					(size 0.7 0.7)
					(thickness 0.15)
				)
				(justify right bottom mirror)
			)
		)
		(property "Datasheet" "https://www.yageo.com/en/Chart/Download/pdf/CC0402MRX5R5BB106"
			(at 0 0 90)
			(layer "F.Fab")
			(hide yes)
			(effects
				(font
					(size 1.27 1.27)
					(thickness 0.15)
				)
			)
		)
		(property "Description" "SMD Multilayer Ceramic Capacitor, 10 µF, 6.3 V, 0402 [1005 Metric], ± 20%, X5R, CC Series"
			(at 0 0 90)
			(layer "F.Fab")
			(hide yes)
			(effects
				(font
					(size 1.27 1.27)
					(thickness 0.15)
				)
			)
		)
		(property "Author" "Antmicro"
			(at 370.195 -75.605 0)
			(layer "B.Fab")
			(hide yes)
			(effects
				(font
					(size 1 1)
					(thickness 0.15)
				)
				(justify mirror)
			)
		)
		(property "Dielectric" ""
			(at 370.195 -75.605 0)
			(layer "B.Fab")
			(hide yes)
			(effects
				(font
					(size 1 1)
					(thickness 0.15)
				)
				(justify mirror)
			)
		)
		(property "License" "Apache-2.0"
			(at 370.195 -75.605 0)
			(layer "B.Fab")
			(hide yes)
			(effects
				(font
					(size 1 1)
					(thickness 0.15)
				)
				(justify mirror)
			)
		)
		(property "MPN" "CC0402MRX5R5BB106"
			(at 370.195 -75.605 0)
			(layer "B.Fab")
			(hide yes)
			(effects
				(font
					(size 1 1)
					(thickness 0.15)
				)
				(justify mirror)
			)
		)
		(property "Manufacturer" "YAGEO"
			(at 370.195 -75.605 0)
			(layer "B.Fab")
			(hide yes)
			(effects
				(font
					(size 1 1)
					(thickness 0.15)
				)
				(justify mirror)
			)
		)
		(property "Public" ""
			(at 370.195 -75.605 0)
			(layer "B.Fab")
			(hide yes)
			(effects
				(font
					(size 1 1)
					(thickness 0.15)
				)
				(justify mirror)
			)
		)
		(property "Val" "10u"
			(at 370.195 -75.605 0)
			(layer "B.Fab")
			(hide yes)
			(effects
				(font
					(size 1 1)
					(thickness 0.15)
				)
				(justify mirror)
			)
		)
		(property "Voltage" ""
			(at 370.195 -75.605 0)
			(layer "B.Fab")
			(hide yes)
			(effects
				(font
					(size 1 1)
					(thickness 0.15)
				)
				(justify mirror)
			)
		)
		(sheetname "/WiFi_Bluetooth/")
		(sheetfile "wifi_bt.kicad_sch")
		(attr smd)
		(fp_rect
			(start -0.925 0.47)
			(end 0.925 -0.47)
			(stroke
				(width 0.05)
				(type default)
			)
			(fill no)
			(layer "B.CrtYd")
		)
		(fp_line
			(start 0.504 -0.248)
			(end -0.494 -0.248)
			(stroke
				(width 0.15)
				(type solid)
			)
			(layer "B.Fab")
		)
		(fp_line
			(start -0.494 -0.248)
			(end -0.494 0.25)
			(stroke
				(width 0.15)
				(type solid)
			)
			(layer "B.Fab")
		)
		(fp_line
			(start 0.504 0.25)
			(end 0.504 -0.248)
			(stroke
				(width 0.15)
				(type solid)
			)
			(layer "B.Fab")
		)
		(fp_line
			(start -0.494 0.25)
			(end 0.504 0.25)
			(stroke
				(width 0.15)
				(type solid)
			)
			(layer "B.Fab")
		)
		(fp_text user "${REFERENCE}"
			(at -0.939 -4.599 270)
			(layer "B.Fab")
			(effects
				(font
					(size 0.7 0.7)
					(thickness 0.15)
				)
				(justify left bottom mirror)
			)
		)
		(fp_text user "License: Apache-2.0"
			(at -0.939 -5.799 270)
			(layer "B.Fab")
			(effects
				(font
					(size 0.7 0.7)
					(thickness 0.15)
				)
				(justify left bottom mirror)
			)
		)
		(fp_text user "Author: Antmicro"
			(at -0.939 -3.399 270)
			(layer "B.Fab")
			(effects
				(font
					(size 0.7 0.7)
					(thickness 0.15)
				)
				(justify left bottom mirror)
			)
		)
		(pad "1" smd roundrect
			(at -0.48 0 90)
			(size 0.59 0.64)
			(layers "B.Cu" "B.Mask" "B.Paste")
			(roundrect_rratio 0.25)
			(net 417 "GND")
			(pintype "passive")
		)
		(pad "2" smd roundrect
			(at 0.48 0 90)
			(size 0.59 0.64)
			(layers "B.Cu" "B.Mask" "B.Paste")
			(roundrect_rratio 0.25)
			(net 50 "+3V3")
			(pintype "passive")
		)
	)
	(footprint "antmicro-footprints:R_Array_4x0201_Panasonic_EXB18V"
		(layer "B.Cu")
		(at 196.75 121.65 -90)
		(property "Reference" "R24"
			(at 1.15 -1.625 90)
			(layer "B.SilkS")
			(effects
				(font
					(size 0.7 0.7)
					(thickness 0.15)
				)
				(justify right bottom mirror)
			)
		)
		(property "Value" "R_4x0R_0201_array"
			(at -1.1 -1.8 90)
			(layer "B.Fab")
			(hide yes)
			(effects
				(font
					(size 0.7 0.7)
					(thickness 0.15)
				)
				(justify left bottom mirror)
			)
		)
		(property "Datasheet" "http://industrial.panasonic.com/cdbs/www-data/pdf/AOC0000/AOC0000C14.pdf"
			(at 0 0 270)
			(layer "F.Fab")
			(hide yes)
			(effects
				(font
					(size 1.27 1.27)
					(thickness 0.15)
				)
			)
		)
		(property "Description" "Zero Ohm Network Resistor, Jumper, 0201 [0603 Metric], Thick Film, Isolated, Flat, 4 Resistors"
			(at 0 0 270)
			(layer "F.Fab")
			(hide yes)
			(effects
				(font
					(size 1.27 1.27)
					(thickness 0.15)
				)
			)
		)
		(property "Author" "Antmicro"
			(at 75.1 318.4 0)
			(layer "B.Fab")
			(hide yes)
			(effects
				(font
					(size 1 1)
					(thickness 0.15)
				)
				(justify mirror)
			)
		)
		(property "License" "Apache-2.0"
			(at 75.1 318.4 0)
			(layer "B.Fab")
			(hide yes)
			(effects
				(font
					(size 1 1)
					(thickness 0.15)
				)
				(justify mirror)
			)
		)
		(property "MPN" "EXB-18VR000X"
			(at 75.1 318.4 0)
			(layer "B.Fab")
			(hide yes)
			(effects
				(font
					(size 1 1)
					(thickness 0.15)
				)
				(justify mirror)
			)
		)
		(property "Manufacturer" "Panasonic"
			(at 75.1 318.4 0)
			(layer "B.Fab")
			(hide yes)
			(effects
				(font
					(size 1 1)
					(thickness 0.15)
				)
				(justify mirror)
			)
		)
		(property "Val" "4x0R_0201"
			(at 75.1 318.4 0)
			(layer "B.Fab")
			(hide yes)
			(effects
				(font
					(size 1 1)
					(thickness 0.15)
				)
				(justify mirror)
			)
		)
		(sheetname "/FPGA MSSIO/")
		(sheetfile "fpga-mssio.kicad_sch")
		(attr smd)
		(fp_line
			(start -0.8 0.45)
			(end -0.8 -0.45)
			(stroke
				(width 0.12)
				(type solid)
			)
			(layer "B.SilkS")
		)
		(fp_line
			(start 0.8 0.45)
			(end 0.8 -0.45)
			(stroke
				(width 0.12)
				(type solid)
			)
			(layer "B.SilkS")
		)
		(fp_rect
			(start -0.898 0.66)
			(end 0.898 -0.65)
			(stroke
				(width 0.05)
				(type solid)
			)
			(fill no)
			(layer "B.CrtYd")
		)
		(fp_text user "License: Apache-2.0"
			(at -1.051 -6 90)
			(layer "B.Fab")
			(effects
				(font
					(size 0.7 0.7)
					(thickness 0.15)
				)
				(justify left bottom mirror)
			)
		)
		(fp_text user "${REFERENCE}"
			(at -1.051 -3.2 90)
			(layer "B.Fab")
			(effects
				(font
					(size 0.7 0.7)
					(thickness 0.15)
				)
				(justify left bottom mirror)
			)
		)
		(fp_text user "Author: Antmicro"
			(at -1.051 -4.599 90)
			(layer "B.Fab")
			(effects
				(font
					(size 0.7 0.7)
					(thickness 0.15)
				)
				(justify left bottom mirror)
			)
		)
		(pad "1" smd roundrect
			(at -0.6 -0.298 270)
			(size 0.2 0.4)
			(layers "B.Cu" "B.Mask" "B.Paste")
			(roundrect_rratio 0.25)
			(net 264 "/FPGA MSSIO/EMMC.CLK")
			(pinfunction "R1.1")
			(pintype "passive")
		)
		(pad "2" smd roundrect
			(at -0.202 -0.298 270)
			(size 0.2 0.4)
			(layers "B.Cu" "B.Mask" "B.Paste")
			(roundrect_rratio 0.25)
			(net 391 "/FPGA MSSIO/EMMC.CMD")
			(pinfunction "R2.1")
			(pintype "passive")
		)
		(pad "3" smd roundrect
			(at 0.2 -0.298 270)
			(size 0.2 0.4)
			(layers "B.Cu" "B.Mask" "B.Paste")
			(roundrect_rratio 0.25)
			(net 390 "/FPGA MSSIO/EMMC.STRB")
			(pinfunction "R3.1")
			(pintype "passive")
		)
		(pad "4" smd roundrect
			(at 0.598 -0.298 270)
			(size 0.2 0.4)
			(layers "B.Cu" "B.Mask" "B.Paste")
			(roundrect_rratio 0.25)
			(net 630 "unconnected-(R24-R4.1-Pad4)")
			(pinfunction "R4.1")
			(pintype "passive+no_connect")
		)
		(pad "5" smd roundrect
			(at 0.598 0.3 270)
			(size 0.2 0.4)
			(layers "B.Cu" "B.Mask" "B.Paste")
			(roundrect_rratio 0.25)
			(net 631 "unconnected-(R24-R4.2-Pad5)")
			(pinfunction "R4.2")
			(pintype "passive+no_connect")
		)
		(pad "6" smd roundrect
			(at 0.2 0.3 270)
			(size 0.2 0.4)
			(layers "B.Cu" "B.Mask" "B.Paste")
			(roundrect_rratio 0.25)
			(net 624 "/FPGA MSSIO/MEM.STRB")
			(pinfunction "R3.2")
			(pintype "passive")
		)
		(pad "7" smd roundrect
			(at -0.202 0.3 270)
			(size 0.2 0.4)
			(layers "B.Cu" "B.Mask" "B.Paste")
			(roundrect_rratio 0.25)
			(net 625 "/FPGA MSSIO/MEM.CMD")
			(pinfunction "R2.2")
			(pintype "passive")
		)
		(pad "8" smd roundrect
			(at -0.6 0.3 270)
			(size 0.2 0.4)
			(layers "B.Cu" "B.Mask" "B.Paste")
			(roundrect_rratio 0.25)
			(net 265 "/FPGA MSSIO/MEM.CLK")
			(pinfunction "R1.2")
			(pintype "passive")
		)
	)
	(footprint "antmicro-footprints:C_0402_1005Metric"
		(layer "B.Cu")
		(at 182.4 136.775 180)
		(descr "Capacitor SMD 0402")
		(tags "capacitor SMD 0402")
		(property "Reference" "C128"
			(at -1.92 0.425 180)
			(layer "B.SilkS")
			(effects
				(font
					(size 0.7 0.7)
					(thickness 0.15)
				)
				(justify left bottom mirror)
			)
		)
		(property "Value" "C_1u_0402"
			(at -1.022927 -2.155213 0)
			(layer "B.Fab")
			(hide yes)
			(effects
				(font
					(size 0.7 0.7)
					(thickness 0.15)
				)
				(justify left bottom mirror)
			)
		)
		(property "Datasheet" "https://product.tdk.com/en/search/capacitor/ceramic/mlcc/info?part_no=C1005X6S1A105K050BC"
			(at 0 0 180)
			(layer "F.Fab")
			(hide yes)
			(effects
				(font
					(size 1.27 1.27)
					(thickness 0.15)
				)
			)
		)
		(property "Description" "SMD Multilayer Ceramic Capacitor, 1 µF, 10 V, 0402 [1005 Metric], ± 10%, X6S, C"
			(at 0 0 180)
			(layer "F.Fab")
			(hide yes)
			(effects
				(font
					(size 1.27 1.27)
					(thickness 0.15)
				)
			)
		)
		(property "Author" "Antmicro"
			(at 364.8 273.55 0)
			(layer "B.Fab")
			(hide yes)
			(effects
				(font
					(size 1 1)
					(thickness 0.15)
				)
				(justify mirror)
			)
		)
		(property "Dielectric" "X5R"
			(at 364.8 273.55 0)
			(layer "B.Fab")
			(hide yes)
			(effects
				(font
					(size 1 1)
					(thickness 0.15)
				)
				(justify mirror)
			)
		)
		(property "License" "Apache-2.0"
			(at 364.8 273.55 0)
			(layer "B.Fab")
			(hide yes)
			(effects
				(font
					(size 1 1)
					(thickness 0.15)
				)
				(justify mirror)
			)
		)
		(property "MPN" "C1005X6S1A105K050BC"
			(at 364.8 273.55 0)
			(layer "B.Fab")
			(hide yes)
			(effects
				(font
					(size 1 1)
					(thickness 0.15)
				)
				(justify mirror)
			)
		)
		(property "Manufacturer" "TDK"
			(at 364.8 273.55 0)
			(layer "B.Fab")
			(hide yes)
			(effects
				(font
					(size 1 1)
					(thickness 0.15)
				)
				(justify mirror)
			)
		)
		(property "Public" ""
			(at 364.8 273.55 0)
			(layer "B.Fab")
			(hide yes)
			(effects
				(font
					(size 1 1)
					(thickness 0.15)
				)
				(justify mirror)
			)
		)
		(property "Val" "1u"
			(at 364.8 273.55 0)
			(layer "B.Fab")
			(hide yes)
			(effects
				(font
					(size 1 1)
					(thickness 0.15)
				)
				(justify mirror)
			)
		)
		(property "Voltage" "16V"
			(at 364.8 273.55 0)
			(layer "B.Fab")
			(hide yes)
			(effects
				(font
					(size 1 1)
					(thickness 0.15)
				)
				(justify mirror)
			)
		)
		(sheetname "/LPDDR4/")
		(sheetfile "lpddr.kicad_sch")
		(attr smd)
		(fp_rect
			(start -0.925 0.47)
			(end 0.925 -0.47)
			(stroke
				(width 0.05)
				(type default)
			)
			(fill no)
			(layer "B.CrtYd")
		)
		(fp_line
			(start 0.504 0.25)
			(end 0.504 -0.248)
			(stroke
				(width 0.15)
				(type solid)
			)
			(layer "B.Fab")
		)
		(fp_line
			(start 0.504 -0.248)
			(end -0.494 -0.248)
			(stroke
				(width 0.15)
				(type solid)
			)
			(layer "B.Fab")
		)
		(fp_line
			(start -0.494 0.25)
			(end 0.504 0.25)
			(stroke
				(width 0.15)
				(type solid)
			)
			(layer "B.Fab")
		)
		(fp_line
			(start -0.494 -0.248)
			(end -0.494 0.25)
			(stroke
				(width 0.15)
				(type solid)
			)
			(layer "B.Fab")
		)
		(fp_text user "Author: Antmicro"
			(at -0.939 -3.399 0)
			(layer "B.Fab")
			(effects
				(font
					(size 0.7 0.7)
					(thickness 0.15)
				)
				(justify left bottom mirror)
			)
		)
		(fp_text user "License: Apache-2.0"
			(at -0.939 -5.799 0)
			(layer "B.Fab")
			(effects
				(font
					(size 0.7 0.7)
					(thickness 0.15)
				)
				(justify left bottom mirror)
			)
		)
		(fp_text user "${REFERENCE}"
			(at -0.939 -4.599 0)
			(layer "B.Fab")
			(effects
				(font
					(size 0.7 0.7)
					(thickness 0.15)
				)
				(justify left bottom mirror)
			)
		)
		(pad "1" smd roundrect
			(at -0.48 0 180)
			(size 0.59 0.64)
			(layers "B.Cu" "B.Mask" "B.Paste")
			(roundrect_rratio 0.25)
			(net 417 "GND")
			(pintype "passive")
		)
		(pad "2" smd roundrect
			(at 0.48 0 180)
			(size 0.59 0.64)
			(layers "B.Cu" "B.Mask" "B.Paste")
			(roundrect_rratio 0.25)
			(net 2 "+1V1")
			(pintype "passive")
		)
	)
)
